FILE_TYPE = CONNECTIVITY;
{Allegro Design Entry HDL 17.2-2016 S081 (4005846) 1/11/2022}
"PAGE_NUMBER" = 260;
0"NC";
1"PVCCINFAON_CPU0\g";
2"P12V_AUX\g";
3"P3V3_AUX\g";
4"P3V3_AUX\g";
5"PVNN_TERM_CPU0\g";
6"PVCCFA_EHV_CPU0\g";
7"P3V3_AUX\g";
8"P3V3_AUX\g";
9"P3V3_AUX\g";
10"GND\g";
11"GND\g";
12"GND\g";
13"GND\g";
14"GND\g";
15"GND\g";
16"GND\g";
17"GND\g";
18"GND\g";
19"GND\g";
20"GND\g";
21"GND\g";
22"GND\g";
23"GND\g";
24"GND\g";
25"GND\g";
26"GND\g";
27"GND\g";
28"GND\g";
29"GND\g";
30"GND\g";
31"NC_PVCCINFAON_CPU0_APWM3";
32"VSENSE_PVCCINFAON_CPU0_DN";
33"PVCCFA_EHV_CPU0_BPWM1";
34"PVCCFA_EHV_CPU0_BCSP1";
35"IRQ_PVCCFA_CPU0_VRHOT_N";
36"PVCCFA_EHV_CPU0_EN_R";
37"SMB_CLK_PVCCINFAON_CPU0";
38"SVID_DIO_PVCCINFAON_CPU0_R";
39"SVID_ALERT_PVCCINFAON_CPU0_R";
40"PWRGD_PVCCFA_EHV_CPU0_R";
41"SVID_CLK_PVCCINFAON_CPU0_R";
42"NC_PVCCINFAON_CPU0_SMB_ALERT";
43"PVCCINFAON_CPU0_EN_R";
44"SMB_DIO_PVCCINFAON_CPU0";
45"SH_PVCCINFAON_CPU0_R";
46"PWRGD_PVCCINFAON_CPU0_R";
47"PVCCINFAON_CPU0_CSPIN";
48"PVCCINFAON_CPU0_VIN_CSNIN";
49"PVCCINFAON_CPU0_PIN_ALERT";
50"SH_PVCCFA_EHV_CPU0_R";
51"VSENSE_PVCCFA_EHV_CPU0_DN";
52"PVCCINFAON_CPU0_VR_FAULT";
53"PVCCINFAON_CPU0_ADDR";
54"PVCCINFAON_CPU0_ATSEN";
55"NC_PVCCINFAON_CPU0_ACSP6";
56"NC_PVCCINFAON_CPU0_APWM6";
57"NC_PVCCINFAON_CPU0_ACSP5";
58"NC_PVCCINFAON_CPU0_APWM5";
59"PVCCINFAON_CPU0_APWM1";
60"NC_PVCCINFAON_CPU0_ACSP7";
61"PVCCFA_EHV_CPU0_BTSEN";
62"PVCCINFAON_CPU0_VREF";
63"PVCCINFAON_CPU0_APWM2";
64"NC_PVCCINFAON_CPU0_APWM7";
65"NC_PVCCINFAON_CPU0_APWM4";
66"NC_PVCCINFAON_CPU0_ACSP4";
67"NC_PVCCINFAON_CPU0_ACSP3";
68"PVCCINFAON_CPU0_ACSP2";
69"PVCCINFAON_CPU0_VCC";
70"PVCCINFAON_CPU0_ACSP1";
71"IRQ_PVCCFA_CPU0_VRHOT_R_N";
72"FM_PVCCFA_EHV_CPU0_EN";
73"VSENSE_PVCCFA_EHV_CPU0_DP";
74"SMB_VR_3V3AUX_SCL_R2";
75"SMB_VR_3V3AUX_SDA_R2";
76"SVID_CLK0_CPU0_R";
77"FM_PVCCINFAON_CPU0_EN";
78"SVID_DIO0_CPU0_R";
79"PWRGD_PVCCINFAON_CPU0";
80"SVID_ALERT0_CPU0_R_N";
81"SH_PVCCFA_EHV_CPU0";
82"SH_PVCCINFAON_CPU0";
83"PVCCINFAON_CPU0_VREF";
84"PWRGD_PVCCFA_EHV_CPU0";
85"VSENSE_PVCCINFAON_CPU0_DP";
%"Q_RES"
"1","(-9275,2225)","0","pure_quanta","I10";
;
PART_NUMBER"CS00002JB13"
VALUE"0"
TOLERANCE"5%"
PACK_TYPE"0402LF"
MATERIAL"EMPTY"
LOCATION"PR107"
CDS_LIB"pure_quanta"
WATTAGE"1/16W"
LOCATION"PR107"
$SEC"1"
CDS_SEC"1";
"B"
$PN"2"47;
"A"
$PN"1"2;
%"Q_RES"
"1","(-4850,7575)","0","pure_quanta","I100";
;
PART_NUMBER"CS-1002FB04"
MATERIAL"CHIP"
WATTAGE"1/16W"
TOLERANCE"1%"
VALUE"1"
PACK_TYPE"0402LF"
LOCATION"PR130"
CDS_LIB"pure_quanta"
LOCATION"PR130"
$SEC"1"
CDS_SEC"1";
"B"
$PN"2"9;
"A"
$PN"1"69;
%"UNIVERSAL_GND"
"1","(-4725,6700)","3","logical_power","I101";
;
HDL_POWER"GND"
CDS_LIB"logical_power";
"A"28;
%"UNIVERSAL_GND"
"1","(-4725,7175)","3","logical_power","I103";
;
HDL_POWER"GND"
CDS_LIB"logical_power";
"A"29;
%"VCC15"
"1","(-4375,7700)","0","logical_power","I104";
;
HDL_POWER"P3V3_AUX"
CDS_LIB"logical_power";
"A"9;
%"UNIVERSAL_GND"
"1","(-3750,2225)","0","logical_power","I105";
;
HDL_POWER"GND"
CDS_LIB"logical_power";
"A"30;
%"Q_RES"
"2","(-3750,2475)","0","pure_quanta","I106";
;
PART_NUMBER"CS31002FB08"
PACK_TYPE"0402LF"
WATTAGE"1/16W"
MATERIAL"EMPTY"
TOLERANCE"1%"
VALUE"10K"
LOCATION"PR436"
CDS_LIB"pure_quanta"
$SEC"1"
CDS_SEC"1";
"A"
$PN"1"61;
"B"
$PN"2"30;
%"Q_RES"
"2","(-9750,2250)","0","pure_quanta","I109";
;
PART_NUMBER"CS16812FB02"
TOLERANCE"1%"
VALUE"681"
PACK_TYPE"0402LF"
MATERIAL"CHIP"
WATTAGE"1/16W"
LOCATION"PR106"
CDS_LIB"pure_quanta"
$SEC"1"
CDS_SEC"1";
"A"
$PN"1"53;
"B"
$PN"2"11;
%"Q_RES"
"1","(-9025,2775)","0","pure_quanta","I11";
;
PART_NUMBER"CS00002JB13"
WATTAGE"1/16W"
TOLERANCE"5%"
VALUE"0"
MATERIAL"CHIP"
PACK_TYPE"0402LF"
LOCATION"R2397"
CDS_LIB"pure_quanta"
LOCATION"R2397"
$SEC"1"
CDS_SEC"1";
"B"
$PN"2"40;
"A"
$PN"1"84;
%"Q_CAP"
"1","(-5925,7375)","0","pure_quanta","I110";
;
PART_NUMBER"CH4104K1B00"
PACK_TYPE"0402"
VALUE"0.1UF"
VOLTAGE"25V"
TOLERANCE"10%"
MATERIAL"EMPTY"
LOCATION"PC2362"
CDS_LIB"pure_quanta"
$SEC"1"
CDS_SEC"1";
"B"
$PN"2"29;
"A"
$PN"1"69;
%"VCC15"
"1","(-9500,3025)","0","logical_power","I12";
;
HDL_POWER"P3V3_AUX"
CDS_LIB"logical_power";
"A"3;
%"Q_RES"
"1","(-9025,2925)","0","pure_quanta","I13";
;
PART_NUMBER"CS21002FB06"
TOLERANCE"1%"
PACK_TYPE"0402LF"
WATTAGE"1/16W"
MATERIAL"CHIP"
VALUE"1K"
LOCATION"R2396"
CDS_LIB"pure_quanta"
LOCATION"R2396"
$SEC"1"
CDS_SEC"1";
"B"
$PN"2"40;
"A"
$PN"1"3;
%"Q_RES"
"1","(-9025,3175)","0","pure_quanta","I14";
;
PART_NUMBER"CS00002JB13"
TOLERANCE"5%"
VALUE"0"
PACK_TYPE"0402LF"
WATTAGE"1/16W"
MATERIAL"CHIP"
LOCATION"R2394"
CDS_LIB"pure_quanta"
LOCATION"R2394"
$SEC"1"
CDS_SEC"1";
"B"
$PN"2"36;
"A"
$PN"1"72;
%"UNIVERSAL_GND"
"1","(-9350,3850)","0","logical_power","I15";
;
HDL_POWER"GND"
CDS_LIB"logical_power";
"A"12;
%"VCC15"
"1","(-9350,3700)","0","logical_power","I16";
;
HDL_POWER"P3V3_AUX"
CDS_LIB"logical_power";
"A"4;
%"Q_RES"
"1","(-9025,3475)","0","pure_quanta","I17";
;
PART_NUMBER"CS21002FB06"
VALUE"1K"
TOLERANCE"1%"
PACK_TYPE"0402LF"
LOCATION"R2393"
CDS_LIB"pure_quanta"
WATTAGE"1/16W"
MATERIAL"CHIP"
$SEC"1"
CDS_SEC"1";
"B"
$PN"2"49;
"A"
$PN"1"4;
%"Q_RES"
"1","(-9025,3575)","0","pure_quanta","I18";
;
PART_NUMBER"CS21002FB06"
MATERIAL"CHIP"
TOLERANCE"1%"
WATTAGE"1/16W"
PACK_TYPE"0402LF"
VALUE"1K"
LOCATION"R2392"
CDS_LIB"pure_quanta"
$SEC"1"
CDS_SEC"1";
"B"
$PN"2"52;
"A"
$PN"1"4;
%"Q_RES"
"2","(-8825,1925)","0","pure_quanta","I19";
;
PART_NUMBER"CS00002JB13"
MATERIAL"CHIP"
WATTAGE"1/16W"
VALUE"0"
PACK_TYPE"0402LF"
TOLERANCE"5%"
LOCATION"PR4220"
CDS_LIB"pure_quanta"
$SEC"1"
CDS_SEC"1";
"A"
$PN"1"47;
"B"
$PN"2"10;
%"Q_CAP"
"1","(-8500,1925)","0","pure_quanta","I20";
;
PART_NUMBER"CH4104K1B00"
MATERIAL"EMPTY"
PACK_TYPE"0402"
TOLERANCE"10%"
VOLTAGE"25V"
VALUE"0.1UF"
LOCATION"PC214"
CDS_LIB"pure_quanta"
LOCATION"PC214"
$SEC"1"
CDS_SEC"1";
"B"
$PN"2"10;
"A"
$PN"1"47;
%"Q_RES"
"2","(-8075,1925)","0","pure_quanta","I21";
;
PART_NUMBER"CS21002FB06"
VALUE"1K"
WATTAGE"1/16W"
MATERIAL"EMPTY"
TOLERANCE"1%"
PACK_TYPE"0402LF"
LOCATION"PR123"
CDS_LIB"pure_quanta"
LOCATION"PR123"
$SEC"1"
CDS_SEC"1";
"A"
$PN"1"48;
"B"
$PN"2"14;
%"Q_CAP"
"2","(-8225,2925)","0","pure_quanta","I22";
;
PART_NUMBER"TMP_QCH21006JB10"
TOLERANCE"5%"
MATERIAL"EMPTY"
VOLTAGE"50V"
VALUE"1000PF"
PACK_TYPE"0402"
LOCATION"C3276"
CDS_LIB"pure_quanta"
LOCATION"C3276"
$SEC"1"
CDS_SEC"1";
"A"
$PN"1"40;
"B"
$PN"2"16;
%"Q_CAP"
"2","(-8225,3050)","0","pure_quanta","I23";
;
PART_NUMBER"TMP_QCH21006JB10"
VOLTAGE"50V"
MATERIAL"X7R"
PACK_TYPE"0402"
TOLERANCE"5%"
VALUE"1000PF"
LOCATION"C3275"
CDS_LIB"pure_quanta"
LOCATION"C3275"
$SEC"1"
CDS_SEC"1";
"A"
$PN"1"36;
"B"
$PN"2"17;
%"VCC15"
"1","(-11100,7450)","0","logical_power","I28";
;
HDL_POWER"PVNN_TERM_CPU0"
CDS_LIB"logical_power";
"A"5;
%"Q_RES"
"1","(-10375,7325)","0","pure_quanta","I36";
;
PART_NUMBER"CS04992FB07"
VALUE"49.9"
TOLERANCE"1%"
PACK_TYPE"0402LF"
WATTAGE"1/16W"
MATERIAL"EMPTY"
LOCATION"R2322"
CDS_LIB"pure_quanta"
$SEC"1"
CDS_SEC"1";
"B"
$PN"2"76;
"A"
$PN"1"5;
%"Q_RES"
"1","(-10375,7225)","0","pure_quanta","I37";
;
PART_NUMBER"CS11002FB07"
VALUE"100"
TOLERANCE"1%"
PACK_TYPE"0402LF"
WATTAGE"1/16W"
MATERIAL"EMPTY"
LOCATION"R2386"
CDS_LIB"pure_quanta"
$SEC"1"
CDS_SEC"1";
"B"
$PN"2"78;
"A"
$PN"1"5;
%"Q_RES"
"1","(-9875,3950)","0","pure_quanta","I38";
;
PART_NUMBER"CS11002FB07"
WATTAGE"1/16W"
TOLERANCE"1%"
VALUE"100"
PACK_TYPE"0402LF"
MATERIAL"CHIP"
LOCATION"PR520"
CDS_LIB"pure_quanta"
$SEC"1"
CDS_SEC"1";
"B"
$PN"2"12;
"A"
$PN"1"51;
%"Q_SHORT"
"1","(-9900,4475)","0","pure_quanta","I39";
;
PART_NUMBER"SHORT6"
PACK_TYPE"SM"
MATERIAL"EMPTY"
LOCATION"PJ46"
CDS_LIB"pure_quanta"
NEEDS_NO_SIZE"TRUE"
LOCATION"PJ46"
$SEC"1"
CDS_SEC"1";
"1"
$PN"1"73;
"2"
$PN"2"81;
%"UNIVERSAL_GND"
"1","(-8500,1625)","0","logical_power","I4";
;
HDL_POWER"GND"
CDS_LIB"logical_power";
"A"10;
%"Q_RES"
"1","(-9825,4625)","0","pure_quanta","I40";
;
PART_NUMBER"CS11002FB07"
WATTAGE"1/16W"
PACK_TYPE"0402LF"
MATERIAL"CHIP"
TOLERANCE"1%"
VALUE"100"
LOCATION"PR522"
CDS_LIB"pure_quanta"
$SEC"1"
CDS_SEC"1";
"B"
$PN"2"6;
"A"
$PN"1"73;
%"VCC15"
"1","(-9325,4775)","0","logical_power","I41";
;
HDL_POWER"PVCCFA_EHV_CPU0"
CDS_LIB"logical_power";
"A"6;
%"Q_RES"
"1","(-9875,5050)","0","pure_quanta","I42";
;
PART_NUMBER"CS11002FB07"
WATTAGE"1/16W"
PACK_TYPE"0402LF"
TOLERANCE"1%"
VALUE"100"
MATERIAL"CHIP"
LOCATION"PR519"
CDS_LIB"pure_quanta"
$SEC"1"
CDS_SEC"1";
"B"
$PN"2"13;
"A"
$PN"1"32;
%"Q_SHORT"
"1","(-9900,5575)","0","pure_quanta","I43";
;
PART_NUMBER"SHORT6"
MATERIAL"EMPTY"
PACK_TYPE"SM"
LOCATION"PJ45"
CDS_LIB"pure_quanta"
NEEDS_NO_SIZE"TRUE"
LOCATION"PJ45"
$SEC"1"
CDS_SEC"1";
"1"
$PN"1"85;
"2"
$PN"2"82;
%"Q_RES"
"1","(-9825,5725)","0","pure_quanta","I44";
;
PART_NUMBER"CS11002FB07"
PACK_TYPE"0402LF"
VALUE"100"
TOLERANCE"1%"
WATTAGE"1/16W"
MATERIAL"CHIP"
LOCATION"PR521"
CDS_LIB"pure_quanta"
$SEC"1"
CDS_SEC"1";
"B"
$PN"2"1;
"A"
$PN"1"85;
%"UNIVERSAL_GND"
"1","(-9350,4950)","0","logical_power","I45";
;
HDL_POWER"GND"
CDS_LIB"logical_power";
"A"13;
%"VCC15"
"1","(-9325,5875)","0","logical_power","I46";
;
HDL_POWER"PVCCINFAON_CPU0"
CDS_LIB"logical_power";
"A"1;
%"Q_RES"
"1","(-8850,4475)","0","pure_quanta","I47";
;
PART_NUMBER"CS00002JB13"
VALUE"0"
TOLERANCE"5%"
MATERIAL"CHIP"
PACK_TYPE"0402LF"
WATTAGE"1/16W"
LOCATION"PR121"
CDS_LIB"pure_quanta"
LOCATION"PR121"
$SEC"1"
CDS_SEC"1";
"B"
$PN"2"50;
"A"
$PN"1"81;
%"Q_CAP"
"1","(-8400,4300)","0","pure_quanta","I48";
;
PART_NUMBER"TMP_QCH2336K1B12"
MATERIAL"X7R"
TOLERANCE"10%"
VALUE"3300PF"
VOLTAGE"50V"
PACK_TYPE"0402"
LOCATION"PC216"
CDS_LIB"pure_quanta"
LOCATION"PC216"
$SEC"1"
CDS_SEC"1";
"B"
$PN"2"51;
"A"
$PN"1"50;
%"Q_RES"
"1","(-8850,5575)","0","pure_quanta","I49";
;
PART_NUMBER"CS00002JB13"
MATERIAL"CHIP"
VALUE"0"
PACK_TYPE"0402LF"
WATTAGE"1/16W"
TOLERANCE"5%"
LOCATION"PR120"
CDS_LIB"pure_quanta"
LOCATION"PR120"
$SEC"1"
CDS_SEC"1";
"B"
$PN"2"45;
"A"
$PN"1"82;
%"UNIVERSAL_GND"
"1","(-9750,2025)","0","logical_power","I5";
;
HDL_POWER"GND"
CDS_LIB"logical_power";
"A"11;
%"Q_CAP"
"1","(-8400,5400)","0","pure_quanta","I50";
;
PART_NUMBER"TMP_QCH2336K1B12"
VALUE"3300PF"
PACK_TYPE"0402"
MATERIAL"X7R"
TOLERANCE"10%"
VOLTAGE"50V"
LOCATION"PC215"
CDS_LIB"pure_quanta"
LOCATION"PC215"
$SEC"1"
CDS_SEC"1";
"B"
$PN"2"32;
"A"
$PN"1"45;
%"Q_RES"
"1","(-9200,6275)","0","pure_quanta","I51";
;
PART_NUMBER"CS00002JB13"
MATERIAL"CHIP"
VALUE"0"
TOLERANCE"5%"
WATTAGE"1/16W"
PACK_TYPE"0402LF"
LOCATION"R2391"
CDS_LIB"pure_quanta"
LOCATION"R2391"
$SEC"1"
CDS_SEC"1";
"B"
$PN"2"44;
"A"
$PN"1"75;
%"Q_RES"
"1","(-9200,6825)","0","pure_quanta","I52";
;
PART_NUMBER"CS00002JB13"
MATERIAL"CHIP"
TOLERANCE"5%"
PACK_TYPE"0402LF"
WATTAGE"1/16W"
VALUE"0"
LOCATION"R2389"
CDS_LIB"pure_quanta"
LOCATION"R2389"
$SEC"1"
CDS_SEC"1";
"B"
$PN"2"39;
"A"
$PN"1"80;
%"Q_RES"
"1","(-9200,6425)","0","pure_quanta","I53";
;
PART_NUMBER"CS00002JB13"
PACK_TYPE"0402LF"
MATERIAL"CHIP"
TOLERANCE"5%"
VALUE"0"
WATTAGE"1/16W"
LOCATION"R2390"
SEC_TYPE"0402LF"
CDS_LIB"pure_quanta"
SEC"1";
"B"
$PN"2"37;
"A"
$PN"1"74;
%"VCC15"
"1","(-9625,7825)","0","logical_power","I54";
;
HDL_POWER"P3V3_AUX"
CDS_LIB"logical_power";
"A"7;
%"Q_RES"
"1","(-9200,7425)","0","pure_quanta","I55";
;
PART_NUMBER"CS00002JB13"
TOLERANCE"5%"
VALUE"0"
PACK_TYPE"0402LF"
MATERIAL"CHIP"
WATTAGE"1/16W"
LOCATION"R2594"
CDS_LIB"pure_quanta"
LOCATION"R2594"
$SEC"1"
CDS_SEC"1";
"B"
$PN"2"43;
"A"
$PN"1"77;
%"Q_RES"
"1","(-9200,7125)","0","pure_quanta","I56";
;
PART_NUMBER"CS11502FB07"
MATERIAL"CHIP"
WATTAGE"1/16W"
VALUE"150"
TOLERANCE"1%"
PACK_TYPE"0402LF"
LOCATION"R2596"
CDS_LIB"pure_quanta"
LOCATION"R2596"
$SEC"1"
CDS_SEC"1";
"B"
$PN"2"41;
"A"
$PN"1"76;
%"Q_RES"
"1","(-9200,6975)","0","pure_quanta","I57";
;
PART_NUMBER"CS00002JB13"
PACK_TYPE"0402LF"
TOLERANCE"5%"
VALUE"0"
MATERIAL"CHIP"
WATTAGE"1/16W"
LOCATION"R2388"
CDS_LIB"pure_quanta"
LOCATION"R2388"
$SEC"1"
CDS_SEC"1";
"B"
$PN"2"38;
"A"
$PN"1"78;
%"Q_RES"
"1","(-9200,7575)","0","pure_quanta","I58";
;
PART_NUMBER"CS00002JB13"
WATTAGE"1/16W"
MATERIAL"CHIP"
PACK_TYPE"0402LF"
TOLERANCE"5%"
VALUE"0"
LOCATION"R2595"
CDS_LIB"pure_quanta"
LOCATION"R2595"
$SEC"1"
CDS_SEC"1";
"B"
$PN"2"46;
"A"
$PN"1"79;
%"Q_RES"
"1","(-9200,7725)","0","pure_quanta","I59";
;
PART_NUMBER"CS21002FB06"
PACK_TYPE"0402LF"
MATERIAL"CHIP"
TOLERANCE"1%"
WATTAGE"1/16W"
VALUE"1K"
LOCATION"R2383"
CDS_LIB"pure_quanta"
LOCATION"R2383"
$SEC"1"
CDS_SEC"1";
"B"
$PN"2"46;
"A"
$PN"1"7;
%"Q_CAP"
"2","(-8375,7300)","0","pure_quanta","I60";
;
PART_NUMBER"TMP_QCH21006JB10"
MATERIAL"X7R"
VALUE"1000PF"
VOLTAGE"50V"
TOLERANCE"5%"
PACK_TYPE"0402"
LOCATION"C3274"
CDS_LIB"pure_quanta"
LOCATION"C3274"
$SEC"1"
CDS_SEC"1";
"A"
$PN"1"43;
"B"
$PN"2"22;
%"Q_CAP"
"2","(-8350,7725)","0","pure_quanta","I61";
;
PART_NUMBER"TMP_QCH21006JB10"
MATERIAL"EMPTY"
TOLERANCE"5%"
VALUE"1000PF"
VOLTAGE"50V"
PACK_TYPE"0402"
LOCATION"C3273"
CDS_LIB"pure_quanta"
LOCATION"C3273"
$SEC"1"
CDS_SEC"1";
"A"
$PN"1"46;
"B"
$PN"2"23;
%"UNIVERSAL_GND"
"1","(-7750,1625)","0","logical_power","I62";
;
HDL_POWER"GND"
CDS_LIB"logical_power";
"A"14;
%"Q_CAP"
"1","(-7750,1925)","0","pure_quanta","I63";
;
PART_NUMBER"CH4104K1B00"
VALUE"0.1UF"
TOLERANCE"10%"
MATERIAL"X7R"
PACK_TYPE"0402"
VOLTAGE"25V"
LOCATION"PC221"
CDS_LIB"pure_quanta"
LOCATION"PC221"
$SEC"1"
CDS_SEC"1";
"B"
$PN"2"14;
"A"
$PN"1"48;
%"UNIVERSAL_GND"
"1","(-7575,1900)","0","logical_power","I64";
;
HDL_POWER"GND"
CDS_LIB"logical_power";
"A"15;
%"ISL69260IRAZT"
"1","(-6825,4825)","0","pure_quanta","I65";
;
PART_NUMBER"AL069260000"
VALUE"ISL69260IRAZ-T"
PART_TYPE"SMLF"
MATERIAL"IC"
LOCATION"PU5"
CDS_LIB"pure_quanta"
CDS_LMAN_SYM_OUTLINE"-550,2850,500,-2850"
NEEDS_NO_SIZE"TRUE"
$SEC"1"
CDS_SEC"1";
"CS0"
$PN"30"34;
"PWM0"
$PN"1"33;
"TEMP0"
$PN"35"54;
"ADDR_CFG"
$PN"34"53;
"TH_GND"
$PN"TH"15;
"CFP"
$PN"33"52;
"CS2"
$PN"28"55;
"PWM2"
$PN"3"56;
"CS3"
$PN"27"57;
"PWM3"
$PN"4"58;
"PWM7"
$PN"8"59;
"CS1"
$PN"29"60;
"RGND1"
$PN"31"51;
"VSEN1"
$PN"32"50;
"NPINALERT#||NPSYSCRIT# \B"
$PN"15"49;
"TEMP1||ISYS"
$PN"36"61;
"VINSEN||VSYS"
$PN"38"48;
"VMON||IINSEN||VSYS||ISYS"
$PN"37"47;
"VCCS"
$PN"40"62;
"PWM6"
$PN"7"63;
"PG0"
$PN"12"46;
"PWM1"
$PN"2"64;
"VSEN0"
$PN"21"45;
"PWM5"
$PN"6"31;
"PWM4"
$PN"5"65;
"PMSDA"
$PN"9"44;
"RGND0"
$PN"22"32;
"EN0"
$PN"13"43;
"NPMALERT# \B"
$PN"11"42;
"SVCLK"
$PN"17"41;
"PG1"
$PN"16"40;
"CS4"
$PN"26"66;
"CS5"
$PN"25"67;
"NVRHOT# \B"
$PN"14"35;
"NSVALERT# \B"
$PN"19"39;
"CS6"
$PN"24"68;
"SVDATA"
$PN"18"38;
"PMSCL"
$PN"10"37;
"EN1"
$PN"20"36;
"VCC"
$PN"39"69;
"CS7"
$PN"23"70;
%"UNIVERSAL_GND"
"1","(-7525,2925)","1","logical_power","I66";
;
HDL_POWER"GND"
CDS_LIB"logical_power";
"A"16;
%"UNIVERSAL_GND"
"1","(-7525,3050)","1","logical_power","I67";
;
HDL_POWER"GND"
CDS_LIB"logical_power";
"A"17;
%"UNIVERSAL_GND"
"1","(-6000,1975)","0","logical_power","I68";
;
HDL_POWER"GND"
CDS_LIB"logical_power";
"A"18;
%"Q_CAP"
"1","(-6000,2200)","0","pure_quanta","I69";
;
PART_NUMBER"TMP_QCH14706KB18"
TOLERANCE"10%"
MATERIAL"X7R"
VALUE"470PF"
VOLTAGE"50V"
PACK_TYPE"0402"
LOCATION"PC222"
CDS_LIB"pure_quanta"
LOCATION"PC222"
$SEC"1"
CDS_SEC"1";
"B"
$PN"2"18;
"A"
$PN"1"54;
%"Q_RES"
"1","(-9875,2475)","0","pure_quanta","I7";
;
PART_NUMBER"CS32802FB05"
PACK_TYPE"0402LF"
VALUE"28K"
TOLERANCE"1%"
MATERIAL"EMPTY"
WATTAGE"1/16W"
LOCATION"PR105"
CDS_LIB"pure_quanta"
LOCATION"PR105"
$SEC"1"
CDS_SEC"1";
"B"
$PN"2"53;
"A"
$PN"1"83;
%"UNIVERSAL_GND"
"1","(-5250,1925)","0","logical_power","I70";
;
HDL_POWER"GND"
CDS_LIB"logical_power";
"A"19;
%"Q_RES"
"2","(-5250,2175)","0","pure_quanta","I71";
;
PART_NUMBER"CS31002FB08"
WATTAGE"1/16W"
MATERIAL"EMPTY"
TOLERANCE"1%"
VALUE"10K"
PACK_TYPE"0402LF"
LOCATION"PR435"
CDS_LIB"pure_quanta"
$SEC"1"
CDS_SEC"1";
"A"
$PN"1"54;
"B"
$PN"2"19;
%"UNIVERSAL_GND"
"1","(-4950,2825)","1","logical_power","I72";
;
HDL_POWER"GND"
CDS_LIB"logical_power";
"A"20;
%"Q_CAP"
"2","(-5675,2825)","0","pure_quanta","I73";
;
PART_NUMBER"TMP_QCH14706KB18"
PACK_TYPE"0402"
VOLTAGE"50V"
MATERIAL"X7R"
VALUE"470PF"
TOLERANCE"10%"
LOCATION"PC1271"
CDS_LIB"pure_quanta"
$SEC"1"
CDS_SEC"1";
"A"
$PN"1"61;
"B"
$PN"2"20;
%"Q_RES"
"1","(-5000,3775)","0","pure_quanta","I76";
;
PART_NUMBER"CS00002JB13"
PACK_TYPE"0402LF"
VALUE"0"
MATERIAL"CHIP"
TOLERANCE"5%"
WATTAGE"1/16W"
LOCATION"PR4225"
CDS_LIB"pure_quanta"
$SEC"1"
CDS_SEC"1";
"B"
$PN"2"21;
"A"
$PN"1"60;
%"Q_RES"
"1","(-4700,3075)","0","pure_quanta","I78";
;
PART_NUMBER"CS00002JB13"
MATERIAL"CHIP"
TOLERANCE"5%"
VALUE"0"
WATTAGE"1/16W"
PACK_TYPE"0402LF"
LOCATION"R2597"
CDS_LIB"pure_quanta"
$SEC"1"
CDS_SEC"1";
"B"
$PN"2"71;
"A"
$PN"1"35;
%"Q_RES"
"2","(-4100,3325)","0","pure_quanta","I79";
;
PART_NUMBER"CS21002FB06"
TOLERANCE"1%"
WATTAGE"1/16W"
VALUE"1K"
PACK_TYPE"0402LF"
MATERIAL"CHIP"
LOCATION"R2398"
CDS_LIB"pure_quanta"
LOCATION"R2398"
$SEC"1"
CDS_SEC"1";
"A"
$PN"1"8;
"B"
$PN"2"71;
%"VCC15"
"1","(-9550,2350)","0","logical_power","I8";
;
HDL_POWER"P12V_AUX"
CDS_LIB"logical_power";
"A"2;
%"UNIVERSAL_GND"
"1","(-4400,3700)","0","logical_power","I80";
;
HDL_POWER"GND"
CDS_LIB"logical_power";
"A"21;
%"VCC15"
"1","(-4100,3575)","0","logical_power","I81";
;
HDL_POWER"P3V3_AUX"
CDS_LIB"logical_power";
"A"8;
%"UNIVERSAL_GND"
"1","(-7650,7300)","1","logical_power","I82";
;
HDL_POWER"GND"
CDS_LIB"logical_power";
"A"22;
%"UNIVERSAL_GND"
"1","(-7650,7725)","1","logical_power","I83";
;
HDL_POWER"GND"
CDS_LIB"logical_power";
"A"23;
%"Q_RES"
"1","(-5025,4225)","0","pure_quanta","I84";
;
PART_NUMBER"CS00002JB13"
WATTAGE"1/16W"
VALUE"0"
MATERIAL"CHIP"
TOLERANCE"5%"
PACK_TYPE"0402LF"
LOCATION"PR4224"
CDS_LIB"pure_quanta"
$SEC"1"
CDS_SEC"1";
"B"
$PN"2"24;
"A"
$PN"1"55;
%"Q_RES"
"1","(-5025,4675)","0","pure_quanta","I85";
;
PART_NUMBER"CS00002JB13"
MATERIAL"CHIP"
VALUE"0"
TOLERANCE"5%"
PACK_TYPE"0402LF"
WATTAGE"1/16W"
LOCATION"PR4223"
CDS_LIB"pure_quanta"
$SEC"1"
CDS_SEC"1";
"B"
$PN"2"25;
"A"
$PN"1"57;
%"Q_RES"
"1","(-5025,5125)","0","pure_quanta","I86";
;
PART_NUMBER"CS00002JB13"
MATERIAL"CHIP"
VALUE"0"
TOLERANCE"5%"
PACK_TYPE"0402LF"
WATTAGE"1/16W"
LOCATION"PR4222"
CDS_LIB"pure_quanta"
$SEC"1"
CDS_SEC"1";
"B"
$PN"2"26;
"A"
$PN"1"66;
%"Q_RES"
"1","(-5025,5575)","0","pure_quanta","I87";
;
PART_NUMBER"CS00002JB13"
MATERIAL"CHIP"
VALUE"0"
TOLERANCE"5%"
PACK_TYPE"0402LF"
WATTAGE"1/16W"
LOCATION"PR4221"
CDS_LIB"pure_quanta"
$SEC"1"
CDS_SEC"1";
"B"
$PN"2"27;
"A"
$PN"1"67;
%"UNIVERSAL_GND"
"1","(-4400,4150)","0","logical_power","I88";
;
HDL_POWER"GND"
CDS_LIB"logical_power";
"A"24;
%"UNIVERSAL_GND"
"1","(-4400,4600)","0","logical_power","I89";
;
HDL_POWER"GND"
CDS_LIB"logical_power";
"A"25;
%"Q_RES"
"1","(-9275,2125)","0","pure_quanta","I9";
;
PART_NUMBER"CS00002JB13"
VALUE"0"
MATERIAL"CHIP"
PACK_TYPE"0402LF"
WATTAGE"1/16W"
TOLERANCE"5%"
LOCATION"PR108"
CDS_LIB"pure_quanta"
LOCATION"PR108"
$SEC"1"
CDS_SEC"1";
"B"
$PN"2"48;
"A"
$PN"1"2;
%"UNIVERSAL_GND"
"1","(-4400,5050)","0","logical_power","I90";
;
HDL_POWER"GND"
CDS_LIB"logical_power";
"A"26;
%"UNIVERSAL_GND"
"1","(-4400,5500)","0","logical_power","I91";
;
HDL_POWER"GND"
CDS_LIB"logical_power";
"A"27;
%"Q_CAP"
"1","(-5575,6900)","0","pure_quanta","I92";
;
PART_NUMBER"CH6101MEB03"
VALUE"10UF"
VOLTAGE"6.3V"
MATERIAL"X6S"
TOLERANCE"20%"
PACK_TYPE"C0402"
LOCATION"PC224"
CDS_LIB"pure_quanta"
LOCATION"PC224"
$SEC"1"
CDS_SEC"1";
"B"
$PN"2"28;
"A"
$PN"1"62;
%"Q_CAP"
"1","(-5175,6900)","0","pure_quanta","I95";
;
PART_NUMBER"CH5103KEB01"
VALUE"1UF"
MATERIAL"X6S"
PACK_TYPE"C0402"
TOLERANCE"10%"
VOLTAGE"16V"
LOCATION"PC1372"
CDS_LIB"pure_quanta"
$SEC"1"
CDS_SEC"1";
"B"
$PN"2"28;
"A"
$PN"1"62;
%"Q_CAP"
"1","(-5575,7375)","0","pure_quanta","I98";
;
PART_NUMBER"CH4106K1B01"
TOLERANCE"10%"
PACK_TYPE"C0402"
MATERIAL"EMPTY"
VOLTAGE"50V"
VALUE"100NF"
LOCATION"PC223"
CDS_LIB"pure_quanta"
LOCATION"PC223"
$SEC"1"
CDS_SEC"1";
"B"
$PN"2"29;
"A"
$PN"1"69;
%"Q_CAP"
"1","(-5175,7375)","0","pure_quanta","I99";
;
PART_NUMBER"CH5103KEB01"
TOLERANCE"10%"
MATERIAL"X6S"
PACK_TYPE"C0402"
VALUE"1UF"
VOLTAGE"16V"
LOCATION"PC225"
CDS_LIB"pure_quanta"
LOCATION"PC225"
$SEC"1"
CDS_SEC"1";
"B"
$PN"2"29;
"A"
$PN"1"69;
END.
